# S9S_MB_2U (Grand Teton) — schematic netlist excerpt (pin names and nets, part order shuffled) for the footprints in the layout excerpt that follows; sources: Cadence DE-HDL packaged netlist, KiCad conversion of 03242023_DA0F0TMBIJ0_F0T_Motherboard_J_brd_V01_OCP.brd

C2243  Q_CAP  1UF 25V 10% X6S  pkg C0402  page 226 : A = P3V3 ; B = GND
R2410  Q_RES  33.2 1% CHIP  pkg 0402LF  page 194 : A = SMB_M2_P0_1V8AUX_SDA_R ; B = SMB_M2_P0_1V8AUX_SDA
H76  HOLE  EMPTY  pkg TH  page 311 : \1\ = GND

(kicad_pcb
	(version 20260206)
	(generator "pcbnew")
	(generator_version "10.0")
	(general
		(thickness 1.6)
		(legacy_teardrops no)
	)
	(paper "A4")
	(title_block
		(title "03242023_DA0F0TMBIJ0_F0T_Motherboard_J_brd_V01_OCP.brd")
		(comment 1 "Grand Teton / footprints 3492-3494 of 6105")
	)
	(layers
		(0 "F.Cu" signal "TOP")
		(4 "In1.Cu" signal "GND")
		(6 "In2.Cu" signal "IN1")
		(8 "In3.Cu" signal "GND1")
		(10 "In4.Cu" signal "IN2")
		(12 "In5.Cu" signal "GND2")
		(14 "In6.Cu" signal "IN3")
		(16 "In7.Cu" signal "GND3")
		(18 "In8.Cu" signal "VCC")
		(20 "In9.Cu" signal "VCC1")
		(22 "In10.Cu" signal "GND4")
		(24 "In11.Cu" signal "IN4")
		(26 "In12.Cu" signal "GND5")
		(28 "In13.Cu" signal "IN5")
		(30 "In14.Cu" signal "GND6")
		(32 "In15.Cu" signal "IN6")
		(34 "In16.Cu" signal "GND7")
		(2 "B.Cu" signal "BOTTOM")
		(9 "F.Adhes" user "F.Adhesive")
		(11 "B.Adhes" user "B.Adhesive")
		(13 "F.Paste" user "Package Geometry/Pastemask Top")
		(15 "B.Paste" user "Package Geometry/Pastemask Bottom")
		(5 "F.SilkS" user "Ref Des/Silkscreen Top")
		(7 "B.SilkS" user "Ref Des/Silkscreen Bottom")
		(1 "F.Mask" user "Board Geometry/Soldermask Top")
		(3 "B.Mask" user "Board Geometry/Soldermask Bottom")
		(17 "Dwgs.User" user "User.Drawings")
		(19 "Cmts.User" user "User.Comments")
		(21 "Eco1.User" user "User.Eco1")
		(23 "Eco2.User" user "User.Eco2")
		(25 "Edge.Cuts" user "Board Geometry/Outline")
		(27 "Margin" user)
		(31 "F.CrtYd" user "Package Geometry/Place Bound Top")
		(29 "B.CrtYd" user "Package Geometry/Place Bound Bottom")
		(35 "F.Fab" user "Ref Des/Assembly Top")
		(33 "B.Fab" user "Ref Des/Assembly Bottom")
	)
	(footprint ""
		(layer "F.Cu")
		(at 118.671594 -93.404182 -90)
		(property "Reference" "C2243"
			(at 0 0 270)
			(layer "F.SilkS")
			(hide yes)
			(effects
				(font
					(size 1.27 1.27)
				)
			)
		)
		(property "Value" ""
			(at 0 0 270)
			(layer "F.Fab")
			(effects
				(font
					(size 1.27 1.27)
				)
			)
		)
		(duplicate_pad_numbers_are_jumpers no)
		(fp_line
			(start -0.7874 0.4064)
			(end -0.7874 -0.4064)
			(stroke
				(width 0.1524)
				(type default)
			)
			(layer "F.SilkS")
		)
		(fp_line
			(start 0.7874 0.4064)
			(end -0.7874 0.4064)
			(stroke
				(width 0.1524)
				(type default)
			)
			(layer "F.SilkS")
		)
		(fp_line
			(start -0.7874 -0.4064)
			(end 0.7874 -0.4064)
			(stroke
				(width 0.1524)
				(type default)
			)
			(layer "F.SilkS")
		)
		(fp_line
			(start 0.7874 -0.4064)
			(end 0.7874 0.4064)
			(stroke
				(width 0.1524)
				(type default)
			)
			(layer "F.SilkS")
		)
		(fp_line
			(start -0.67945 0.3048)
			(end -0.67945 -0.305054)
			(stroke
				(width 0.1)
				(type default)
			)
			(layer "F.Fab")
		)
		(fp_line
			(start -0.12065 0.3048)
			(end -0.67945 0.3048)
			(stroke
				(width 0.1)
				(type default)
			)
			(layer "F.Fab")
		)
		(fp_line
			(start 0.120396 0.3048)
			(end 0.120396 0.2794)
			(stroke
				(width 0.1)
				(type default)
			)
			(layer "F.Fab")
		)
		(fp_line
			(start 0.67945 0.3048)
			(end 0.120396 0.3048)
			(stroke
				(width 0.1)
				(type default)
			)
			(layer "F.Fab")
		)
		(fp_line
			(start -0.12065 0.2794)
			(end -0.12065 0.3048)
			(stroke
				(width 0.1)
				(type default)
			)
			(layer "F.Fab")
		)
		(fp_line
			(start 0.120396 0.2794)
			(end -0.12065 0.2794)
			(stroke
				(width 0.1)
				(type default)
			)
			(layer "F.Fab")
		)
		(fp_line
			(start -0.12065 -0.2794)
			(end 0.12065 -0.2794)
			(stroke
				(width 0.1)
				(type default)
			)
			(layer "F.Fab")
		)
		(fp_line
			(start 0.12065 -0.2794)
			(end 0.12065 -0.3048)
			(stroke
				(width 0.1)
				(type default)
			)
			(layer "F.Fab")
		)
		(fp_line
			(start 0.12065 -0.3048)
			(end 0.67945 -0.3048)
			(stroke
				(width 0.1)
				(type default)
			)
			(layer "F.Fab")
		)
		(fp_line
			(start 0.67945 -0.3048)
			(end 0.67945 0.3048)
			(stroke
				(width 0.1)
				(type default)
			)
			(layer "F.Fab")
		)
		(fp_line
			(start -0.67945 -0.305054)
			(end -0.12065 -0.305054)
			(stroke
				(width 0.1)
				(type default)
			)
			(layer "F.Fab")
		)
		(fp_line
			(start -0.12065 -0.305054)
			(end -0.12065 -0.2794)
			(stroke
				(width 0.1)
				(type default)
			)
			(layer "F.Fab")
		)
		(pad "1" smd circle
			(at -0.40005 0 270)
			(size 0 0)
			(layers "F.Cu" "F.Mask" "F.Paste")
			(net "P3V3")
		)
		(pad "2" smd circle
			(at 0.40005 0 270)
			(size 0 0)
			(layers "F.Cu" "F.Mask" "F.Paste")
			(net "GND")
		)
	)
	(footprint ""
		(layer "F.Cu")
		(at 145.34388 -56.225948 180)
		(property "Reference" "R2410"
			(at 0 0 180)
			(layer "F.SilkS")
			(hide yes)
			(effects
				(font
					(size 1.27 1.27)
				)
			)
		)
		(property "Value" ""
			(at 0 0 180)
			(layer "F.Fab")
			(effects
				(font
					(size 1.27 1.27)
				)
			)
		)
		(duplicate_pad_numbers_are_jumpers no)
		(fp_line
			(start 0.7874 0.4064)
			(end -0.7874 0.4064)
			(stroke
				(width 0.1524)
				(type default)
			)
			(layer "F.SilkS")
		)
		(fp_line
			(start 0.7874 -0.4064)
			(end 0.7874 0.4064)
			(stroke
				(width 0.1524)
				(type default)
			)
			(layer "F.SilkS")
		)
		(fp_line
			(start -0.7874 0.4064)
			(end -0.7874 -0.4064)
			(stroke
				(width 0.1524)
				(type default)
			)
			(layer "F.SilkS")
		)
		(fp_line
			(start -0.7874 -0.4064)
			(end 0.7874 -0.4064)
			(stroke
				(width 0.1524)
				(type default)
			)
			(layer "F.SilkS")
		)
		(fp_line
			(start 0.67945 0.3048)
			(end 0.120396 0.3048)
			(stroke
				(width 0.1)
				(type default)
			)
			(layer "F.Fab")
		)
		(fp_line
			(start 0.67945 -0.3048)
			(end 0.67945 0.3048)
			(stroke
				(width 0.1)
				(type default)
			)
			(layer "F.Fab")
		)
		(fp_line
			(start 0.12065 -0.2794)
			(end 0.12065 -0.3048)
			(stroke
				(width 0.1)
				(type default)
			)
			(layer "F.Fab")
		)
		(fp_line
			(start 0.12065 -0.3048)
			(end 0.67945 -0.3048)
			(stroke
				(width 0.1)
				(type default)
			)
			(layer "F.Fab")
		)
		(fp_line
			(start 0.120396 0.3048)
			(end 0.120396 0.2794)
			(stroke
				(width 0.1)
				(type default)
			)
			(layer "F.Fab")
		)
		(fp_line
			(start 0.120396 0.2794)
			(end -0.12065 0.2794)
			(stroke
				(width 0.1)
				(type default)
			)
			(layer "F.Fab")
		)
		(fp_line
			(start -0.12065 0.3048)
			(end -0.67945 0.3048)
			(stroke
				(width 0.1)
				(type default)
			)
			(layer "F.Fab")
		)
		(fp_line
			(start -0.12065 0.2794)
			(end -0.12065 0.3048)
			(stroke
				(width 0.1)
				(type default)
			)
			(layer "F.Fab")
		)
		(fp_line
			(start -0.12065 -0.2794)
			(end 0.12065 -0.2794)
			(stroke
				(width 0.1)
				(type default)
			)
			(layer "F.Fab")
		)
		(fp_line
			(start -0.12065 -0.305054)
			(end -0.12065 -0.2794)
			(stroke
				(width 0.1)
				(type default)
			)
			(layer "F.Fab")
		)
		(fp_line
			(start -0.67945 0.3048)
			(end -0.67945 -0.305054)
			(stroke
				(width 0.1)
				(type default)
			)
			(layer "F.Fab")
		)
		(fp_line
			(start -0.67945 -0.305054)
			(end -0.12065 -0.305054)
			(stroke
				(width 0.1)
				(type default)
			)
			(layer "F.Fab")
		)
		(pad "1" smd circle
			(at -0.40005 0 180)
			(size 0 0)
			(layers "F.Cu" "F.Mask" "F.Paste")
			(net "SMB_M2_P0_1V8AUX_SDA_R")
		)
		(pad "2" smd circle
			(at 0.40005 0 180)
			(size 0 0)
			(layers "F.Cu" "F.Mask" "F.Paste")
			(net "SMB_M2_P0_1V8AUX_SDA")
		)
	)
	(footprint ""
		(layer "F.Cu")
		(at 239.949736 -39.424864)
		(property "Reference" "H76"
			(at -0.155702 -3.208274 0)
			(unlocked yes)
			(layer "B.SilkS")
			(effects
				(font
					(size 0.7874 0.5842)
					(thickness 0.1524)
				)
				(justify left mirror)
			)
		)
		(property "Value" ""
			(at 0 0 0)
			(layer "F.Fab")
			(effects
				(font
					(size 1.27 1.27)
				)
			)
		)
		(duplicate_pad_numbers_are_jumpers no)
		(pad "1" thru_hole rect
			(at 0 0)
			(size 4.2164 5.0038)
			(drill 2.0066
				(offset 0.099822 0)
			)
			(layers "*.Cu" "*.Mask")
			(remove_unused_layers no)
			(net "GND")
			(clearance -0.8509)
			(padstack
				(mode front_inner_back)
				(layer "Inner"
					(shape circle)
					(size 4.0132 4.0132)
					(clearance -0.7493)
				)
				(layer "B.Cu"
					(shape circle)
					(size 4.0132 4.0132)
					(clearance -0.7493)
				)
			)
		)
	)
)
